(kicad_pcb
	(version 20260206)
	(generator "pcbnew")
	(generator_version "10.0")
	(general
		(thickness 1.6)
		(legacy_teardrops no)
	)
	(paper "A4")
	(title_block
		(title "04192023_DAF0TMB3IC0_F0TG_MB_C_brd_V02_OCP.brd")
		(comment 1 "Grand Teton / footprints 1873-1880 of 8354")
	)
	(layers
		(0 "F.Cu" signal "TOP")
		(4 "In1.Cu" signal "GND")
		(6 "In2.Cu" signal "IN1")
		(8 "In3.Cu" signal "GND1")
		(10 "In4.Cu" signal "IN2")
		(12 "In5.Cu" signal "GND2")
		(14 "In6.Cu" signal "IN3")
		(16 "In7.Cu" signal "GND3")
		(18 "In8.Cu" signal "VCC")
		(20 "In9.Cu" signal "VCC1")
		(22 "In10.Cu" signal "GND4")
		(24 "In11.Cu" signal "IN4")
		(26 "In12.Cu" signal "GND5")
		(28 "In13.Cu" signal "IN5")
		(30 "In14.Cu" signal "GND6")
		(32 "In15.Cu" signal "IN6")
		(34 "In16.Cu" signal "GND7")
		(2 "B.Cu" signal "BOTTOM")
		(9 "F.Adhes" user "F.Adhesive")
		(11 "B.Adhes" user "B.Adhesive")
		(13 "F.Paste" user "Package Geometry/Pastemask Top")
		(15 "B.Paste" user "Package Geometry/Pastemask Bottom")
		(5 "F.SilkS" user "Ref Des/Silkscreen Top")
		(7 "B.SilkS" user "Ref Des/Silkscreen Bottom")
		(1 "F.Mask" user "Board Geometry/Soldermask Top")
		(3 "B.Mask" user "Board Geometry/Soldermask Bottom")
		(17 "Dwgs.User" user "User.Drawings")
		(19 "Cmts.User" user "User.Comments")
		(21 "Eco1.User" user "User.Eco1")
		(23 "Eco2.User" user "User.Eco2")
		(25 "Edge.Cuts" user "Board Geometry/Outline")
		(27 "Margin" user)
		(31 "F.CrtYd" user "Package Geometry/Place Bound Top")
		(29 "B.CrtYd" user "Package Geometry/Place Bound Bottom")
		(35 "F.Fab" user "Ref Des/Assembly Top")
		(33 "B.Fab" user "Ref Des/Assembly Bottom")
	)
	(footprint ""
		(layer "F.Cu")
		(at 157.995366 -57.474358)
		(property "Reference" "C2018"
			(at 0 0 0)
			(layer "F.SilkS")
			(hide yes)
			(effects
				(font
					(size 1.27 1.27)
				)
			)
		)
		(property "Value" ""
			(at 0 0 0)
			(layer "F.Fab")
			(effects
				(font
					(size 1.27 1.27)
				)
			)
		)
		(duplicate_pad_numbers_are_jumpers no)
		(fp_line
			(start -0.7874 -0.4064)
			(end 0.7874 -0.4064)
			(stroke
				(width 0.1524)
				(type default)
			)
			(layer "F.SilkS")
		)
		(fp_line
			(start -0.7874 0.4064)
			(end -0.7874 -0.4064)
			(stroke
				(width 0.1524)
				(type default)
			)
			(layer "F.SilkS")
		)
		(fp_line
			(start 0.7874 -0.4064)
			(end 0.7874 0.4064)
			(stroke
				(width 0.1524)
				(type default)
			)
			(layer "F.SilkS")
		)
		(fp_line
			(start 0.7874 0.4064)
			(end -0.7874 0.4064)
			(stroke
				(width 0.1524)
				(type default)
			)
			(layer "F.SilkS")
		)
		(fp_line
			(start -0.67945 -0.305054)
			(end -0.12065 -0.305054)
			(stroke
				(width 0.1)
				(type default)
			)
			(layer "F.Fab")
		)
		(fp_line
			(start -0.67945 0.3048)
			(end -0.67945 -0.305054)
			(stroke
				(width 0.1)
				(type default)
			)
			(layer "F.Fab")
		)
		(fp_line
			(start -0.12065 -0.305054)
			(end -0.12065 -0.2794)
			(stroke
				(width 0.1)
				(type default)
			)
			(layer "F.Fab")
		)
		(fp_line
			(start -0.12065 -0.2794)
			(end 0.12065 -0.2794)
			(stroke
				(width 0.1)
				(type default)
			)
			(layer "F.Fab")
		)
		(fp_line
			(start -0.12065 0.2794)
			(end -0.12065 0.3048)
			(stroke
				(width 0.1)
				(type default)
			)
			(layer "F.Fab")
		)
		(fp_line
			(start -0.12065 0.3048)
			(end -0.67945 0.3048)
			(stroke
				(width 0.1)
				(type default)
			)
			(layer "F.Fab")
		)
		(fp_line
			(start 0.120396 0.2794)
			(end -0.12065 0.2794)
			(stroke
				(width 0.1)
				(type default)
			)
			(layer "F.Fab")
		)
		(fp_line
			(start 0.120396 0.3048)
			(end 0.120396 0.2794)
			(stroke
				(width 0.1)
				(type default)
			)
			(layer "F.Fab")
		)
		(fp_line
			(start 0.12065 -0.3048)
			(end 0.67945 -0.3048)
			(stroke
				(width 0.1)
				(type default)
			)
			(layer "F.Fab")
		)
		(fp_line
			(start 0.12065 -0.2794)
			(end 0.12065 -0.3048)
			(stroke
				(width 0.1)
				(type default)
			)
			(layer "F.Fab")
		)
		(fp_line
			(start 0.67945 -0.3048)
			(end 0.67945 0.3048)
			(stroke
				(width 0.1)
				(type default)
			)
			(layer "F.Fab")
		)
		(fp_line
			(start 0.67945 0.3048)
			(end 0.120396 0.3048)
			(stroke
				(width 0.1)
				(type default)
			)
			(layer "F.Fab")
		)
		(pad "1" smd circle
			(at -0.40005 0)
			(size 0 0)
			(layers "F.Cu" "F.Mask" "F.Paste")
			(net "P3V3")
		)
		(pad "2" smd circle
			(at 0.40005 0)
			(size 0 0)
			(layers "F.Cu" "F.Mask" "F.Paste")
			(net "GND")
		)
	)
	(footprint ""
		(layer "F.Cu")
		(at 200.914 -101.346 180)
		(property "Reference" "R8000"
			(at 0 0 180)
			(layer "F.SilkS")
			(hide yes)
			(effects
				(font
					(size 1.27 1.27)
				)
			)
		)
		(property "Value" ""
			(at 0 0 180)
			(layer "F.Fab")
			(effects
				(font
					(size 1.27 1.27)
				)
			)
		)
		(duplicate_pad_numbers_are_jumpers no)
		(fp_line
			(start 0.7874 0.4064)
			(end -0.7874 0.4064)
			(stroke
				(width 0.1524)
				(type default)
			)
			(layer "F.SilkS")
		)
		(fp_line
			(start 0.7874 -0.4064)
			(end 0.7874 0.4064)
			(stroke
				(width 0.1524)
				(type default)
			)
			(layer "F.SilkS")
		)
		(fp_line
			(start -0.7874 0.4064)
			(end -0.7874 -0.4064)
			(stroke
				(width 0.1524)
				(type default)
			)
			(layer "F.SilkS")
		)
		(fp_line
			(start -0.7874 -0.4064)
			(end 0.7874 -0.4064)
			(stroke
				(width 0.1524)
				(type default)
			)
			(layer "F.SilkS")
		)
		(fp_line
			(start 0.67945 0.3048)
			(end 0.120396 0.3048)
			(stroke
				(width 0.1)
				(type default)
			)
			(layer "F.Fab")
		)
		(fp_line
			(start 0.67945 -0.3048)
			(end 0.67945 0.3048)
			(stroke
				(width 0.1)
				(type default)
			)
			(layer "F.Fab")
		)
		(fp_line
			(start 0.12065 -0.2794)
			(end 0.12065 -0.3048)
			(stroke
				(width 0.1)
				(type default)
			)
			(layer "F.Fab")
		)
		(fp_line
			(start 0.12065 -0.3048)
			(end 0.67945 -0.3048)
			(stroke
				(width 0.1)
				(type default)
			)
			(layer "F.Fab")
		)
		(fp_line
			(start 0.120396 0.3048)
			(end 0.120396 0.2794)
			(stroke
				(width 0.1)
				(type default)
			)
			(layer "F.Fab")
		)
		(fp_line
			(start 0.120396 0.2794)
			(end -0.12065 0.2794)
			(stroke
				(width 0.1)
				(type default)
			)
			(layer "F.Fab")
		)
		(fp_line
			(start -0.12065 0.3048)
			(end -0.67945 0.3048)
			(stroke
				(width 0.1)
				(type default)
			)
			(layer "F.Fab")
		)
		(fp_line
			(start -0.12065 0.2794)
			(end -0.12065 0.3048)
			(stroke
				(width 0.1)
				(type default)
			)
			(layer "F.Fab")
		)
		(fp_line
			(start -0.12065 -0.2794)
			(end 0.12065 -0.2794)
			(stroke
				(width 0.1)
				(type default)
			)
			(layer "F.Fab")
		)
		(fp_line
			(start -0.12065 -0.305054)
			(end -0.12065 -0.2794)
			(stroke
				(width 0.1)
				(type default)
			)
			(layer "F.Fab")
		)
		(fp_line
			(start -0.67945 0.3048)
			(end -0.67945 -0.305054)
			(stroke
				(width 0.1)
				(type default)
			)
			(layer "F.Fab")
		)
		(fp_line
			(start -0.67945 -0.305054)
			(end -0.12065 -0.305054)
			(stroke
				(width 0.1)
				(type default)
			)
			(layer "F.Fab")
		)
		(pad "1" smd circle
			(at -0.40005 0 180)
			(size 0 0)
			(layers "F.Cu" "F.Mask" "F.Paste")
			(net "PRSNT_SWB_ISO_N")
		)
		(pad "2" smd circle
			(at 0.40005 0 180)
			(size 0 0)
			(layers "F.Cu" "F.Mask" "F.Paste")
			(net "PRSNT_SWB_ISO_R_N")
		)
	)
	(footprint ""
		(layer "F.Cu")
		(at 200.914 -104.521 180)
		(property "Reference" "R8081"
			(at 0 0 180)
			(layer "F.SilkS")
			(hide yes)
			(effects
				(font
					(size 1.27 1.27)
				)
			)
		)
		(property "Value" ""
			(at 0 0 180)
			(layer "F.Fab")
			(effects
				(font
					(size 1.27 1.27)
				)
			)
		)
		(duplicate_pad_numbers_are_jumpers no)
		(fp_line
			(start 0.7874 0.4064)
			(end -0.7874 0.4064)
			(stroke
				(width 0.1524)
				(type default)
			)
			(layer "F.SilkS")
		)
		(fp_line
			(start 0.7874 -0.4064)
			(end 0.7874 0.4064)
			(stroke
				(width 0.1524)
				(type default)
			)
			(layer "F.SilkS")
		)
		(fp_line
			(start -0.7874 0.4064)
			(end -0.7874 -0.4064)
			(stroke
				(width 0.1524)
				(type default)
			)
			(layer "F.SilkS")
		)
		(fp_line
			(start -0.7874 -0.4064)
			(end 0.7874 -0.4064)
			(stroke
				(width 0.1524)
				(type default)
			)
			(layer "F.SilkS")
		)
		(fp_line
			(start 0.67945 0.3048)
			(end 0.120396 0.3048)
			(stroke
				(width 0.1)
				(type default)
			)
			(layer "F.Fab")
		)
		(fp_line
			(start 0.67945 -0.3048)
			(end 0.67945 0.3048)
			(stroke
				(width 0.1)
				(type default)
			)
			(layer "F.Fab")
		)
		(fp_line
			(start 0.12065 -0.2794)
			(end 0.12065 -0.3048)
			(stroke
				(width 0.1)
				(type default)
			)
			(layer "F.Fab")
		)
		(fp_line
			(start 0.12065 -0.3048)
			(end 0.67945 -0.3048)
			(stroke
				(width 0.1)
				(type default)
			)
			(layer "F.Fab")
		)
		(fp_line
			(start 0.120396 0.3048)
			(end 0.120396 0.2794)
			(stroke
				(width 0.1)
				(type default)
			)
			(layer "F.Fab")
		)
		(fp_line
			(start 0.120396 0.2794)
			(end -0.12065 0.2794)
			(stroke
				(width 0.1)
				(type default)
			)
			(layer "F.Fab")
		)
		(fp_line
			(start -0.12065 0.3048)
			(end -0.67945 0.3048)
			(stroke
				(width 0.1)
				(type default)
			)
			(layer "F.Fab")
		)
		(fp_line
			(start -0.12065 0.2794)
			(end -0.12065 0.3048)
			(stroke
				(width 0.1)
				(type default)
			)
			(layer "F.Fab")
		)
		(fp_line
			(start -0.12065 -0.2794)
			(end 0.12065 -0.2794)
			(stroke
				(width 0.1)
				(type default)
			)
			(layer "F.Fab")
		)
		(fp_line
			(start -0.12065 -0.305054)
			(end -0.12065 -0.2794)
			(stroke
				(width 0.1)
				(type default)
			)
			(layer "F.Fab")
		)
		(fp_line
			(start -0.67945 0.3048)
			(end -0.67945 -0.305054)
			(stroke
				(width 0.1)
				(type default)
			)
			(layer "F.Fab")
		)
		(fp_line
			(start -0.67945 -0.305054)
			(end -0.12065 -0.305054)
			(stroke
				(width 0.1)
				(type default)
			)
			(layer "F.Fab")
		)
		(pad "1" smd circle
			(at -0.40005 0 180)
			(size 0 0)
			(layers "F.Cu" "F.Mask" "F.Paste")
			(net "PWRGD_CHAF_CPU0_R1")
		)
		(pad "2" smd circle
			(at 0.40005 0 180)
			(size 0 0)
			(layers "F.Cu" "F.Mask" "F.Paste")
			(net "PWRGD_CHAF_CPU0_R2")
		)
	)
	(footprint ""
		(layer "F.Cu")
		(at 144.315688 -395.436852 -90)
		(property "Reference" "R870"
			(at 0 0 270)
			(layer "F.SilkS")
			(hide yes)
			(effects
				(font
					(size 1.27 1.27)
				)
			)
		)
		(property "Value" ""
			(at 0 0 270)
			(layer "F.Fab")
			(effects
				(font
					(size 1.27 1.27)
				)
			)
		)
		(duplicate_pad_numbers_are_jumpers no)
		(fp_line
			(start -0.32512 0.175006)
			(end -0.32512 -0.175006)
			(stroke
				(width 0.1)
				(type default)
			)
			(layer "F.Fab")
		)
		(fp_line
			(start 0.32512 0.175006)
			(end -0.32512 0.175006)
			(stroke
				(width 0.1)
				(type default)
			)
			(layer "F.Fab")
		)
		(fp_line
			(start -0.32512 -0.175006)
			(end 0.32512 -0.175006)
			(stroke
				(width 0.1)
				(type default)
			)
			(layer "F.Fab")
		)
		(fp_line
			(start 0.32512 -0.175006)
			(end 0.32512 0.175006)
			(stroke
				(width 0.1)
				(type default)
			)
			(layer "F.Fab")
		)
		(pad "1" smd rect
			(at -0.2667 0 270)
			(size 0.3048 0.381)
			(layers "F.Cu" "F.Mask" "F.Paste")
			(net "P1V8_CPU1_RT_1D")
		)
		(pad "2" smd rect
			(at 0.2667 0 90)
			(size 0.3048 0.381)
			(layers "F.Cu" "F.Mask" "F.Paste")
			(net "RST_RT_CPU1_P2_RESET_R_N")
		)
	)
	(footprint ""
		(layer "F.Cu")
		(at 154.633422 -52.771294 90)
		(property "Reference" "R3572"
			(at 0 0 90)
			(layer "F.SilkS")
			(hide yes)
			(effects
				(font
					(size 1.27 1.27)
				)
			)
		)
		(property "Value" ""
			(at 0 0 90)
			(layer "F.Fab")
			(effects
				(font
					(size 1.27 1.27)
				)
			)
		)
		(duplicate_pad_numbers_are_jumpers no)
		(fp_line
			(start 0.7874 -0.4064)
			(end 0.7874 0.4064)
			(stroke
				(width 0.1524)
				(type default)
			)
			(layer "F.SilkS")
		)
		(fp_line
			(start -0.7874 -0.4064)
			(end 0.7874 -0.4064)
			(stroke
				(width 0.1524)
				(type default)
			)
			(layer "F.SilkS")
		)
		(fp_line
			(start 0.7874 0.4064)
			(end -0.7874 0.4064)
			(stroke
				(width 0.1524)
				(type default)
			)
			(layer "F.SilkS")
		)
		(fp_line
			(start -0.7874 0.4064)
			(end -0.7874 -0.4064)
			(stroke
				(width 0.1524)
				(type default)
			)
			(layer "F.SilkS")
		)
		(fp_line
			(start -0.12065 -0.305054)
			(end -0.12065 -0.2794)
			(stroke
				(width 0.1)
				(type default)
			)
			(layer "F.Fab")
		)
		(fp_line
			(start -0.67945 -0.305054)
			(end -0.12065 -0.305054)
			(stroke
				(width 0.1)
				(type default)
			)
			(layer "F.Fab")
		)
		(fp_line
			(start 0.67945 -0.3048)
			(end 0.67945 0.3048)
			(stroke
				(width 0.1)
				(type default)
			)
			(layer "F.Fab")
		)
		(fp_line
			(start 0.12065 -0.3048)
			(end 0.67945 -0.3048)
			(stroke
				(width 0.1)
				(type default)
			)
			(layer "F.Fab")
		)
		(fp_line
			(start 0.12065 -0.2794)
			(end 0.12065 -0.3048)
			(stroke
				(width 0.1)
				(type default)
			)
			(layer "F.Fab")
		)
		(fp_line
			(start -0.12065 -0.2794)
			(end 0.12065 -0.2794)
			(stroke
				(width 0.1)
				(type default)
			)
			(layer "F.Fab")
		)
		(fp_line
			(start 0.120396 0.2794)
			(end -0.12065 0.2794)
			(stroke
				(width 0.1)
				(type default)
			)
			(layer "F.Fab")
		)
		(fp_line
			(start -0.12065 0.2794)
			(end -0.12065 0.3048)
			(stroke
				(width 0.1)
				(type default)
			)
			(layer "F.Fab")
		)
		(fp_line
			(start 0.67945 0.3048)
			(end 0.120396 0.3048)
			(stroke
				(width 0.1)
				(type default)
			)
			(layer "F.Fab")
		)
		(fp_line
			(start 0.120396 0.3048)
			(end 0.120396 0.2794)
			(stroke
				(width 0.1)
				(type default)
			)
			(layer "F.Fab")
		)
		(fp_line
			(start -0.12065 0.3048)
			(end -0.67945 0.3048)
			(stroke
				(width 0.1)
				(type default)
			)
			(layer "F.Fab")
		)
		(fp_line
			(start -0.67945 0.3048)
			(end -0.67945 -0.305054)
			(stroke
				(width 0.1)
				(type default)
			)
			(layer "F.Fab")
		)
		(pad "1" smd circle
			(at -0.40005 0 90)
			(size 0 0)
			(layers "F.Cu" "F.Mask" "F.Paste")
			(net "SMB_INA230_4_3V3AUX_SCL_R")
		)
		(pad "2" smd circle
			(at 0.40005 0 90)
			(size 0 0)
			(layers "F.Cu" "F.Mask" "F.Paste")
			(net "SMB_INA230_4_3V3AUX_SCL_R1")
		)
	)
	(footprint ""
		(layer "F.Cu")
		(at 296.385742 -400.1516 -90)
		(property "Reference" "R975"
			(at 0 0 270)
			(layer "F.SilkS")
			(hide yes)
			(effects
				(font
					(size 1.27 1.27)
				)
			)
		)
		(property "Value" ""
			(at 0 0 270)
			(layer "F.Fab")
			(effects
				(font
					(size 1.27 1.27)
				)
			)
		)
		(duplicate_pad_numbers_are_jumpers no)
		(fp_line
			(start -0.32512 0.175006)
			(end -0.32512 -0.175006)
			(stroke
				(width 0.1)
				(type default)
			)
			(layer "F.Fab")
		)
		(fp_line
			(start 0.32512 0.175006)
			(end -0.32512 0.175006)
			(stroke
				(width 0.1)
				(type default)
			)
			(layer "F.Fab")
		)
		(fp_line
			(start -0.32512 -0.175006)
			(end 0.32512 -0.175006)
			(stroke
				(width 0.1)
				(type default)
			)
			(layer "F.Fab")
		)
		(fp_line
			(start 0.32512 -0.175006)
			(end 0.32512 0.175006)
			(stroke
				(width 0.1)
				(type default)
			)
			(layer "F.Fab")
		)
		(pad "1" smd rect
			(at -0.2667 0 270)
			(size 0.3048 0.381)
			(layers "F.Cu" "F.Mask" "F.Paste")
			(net "P1V8_CPU0_RT_1D")
		)
		(pad "2" smd rect
			(at 0.2667 0 90)
			(size 0.3048 0.381)
			(layers "F.Cu" "F.Mask" "F.Paste")
			(net "JTAG_TEST_MODE_RT_CPU0_P0")
		)
	)
	(footprint ""
		(layer "F.Cu")
		(at 128.809496 -375.49963 -90)
		(property "Reference" "C1527"
			(at 0 0 270)
			(layer "F.SilkS")
			(hide yes)
			(effects
				(font
					(size 1.27 1.27)
				)
			)
		)
		(property "Value" ""
			(at 0 0 270)
			(layer "F.Fab")
			(effects
				(font
					(size 1.27 1.27)
				)
			)
		)
		(duplicate_pad_numbers_are_jumpers no)
		(fp_line
			(start -0.299974 0.150114)
			(end -0.299974 -0.150114)
			(stroke
				(width 0.1)
				(type default)
			)
			(layer "F.Fab")
		)
		(fp_line
			(start 0.299974 0.150114)
			(end -0.299974 0.150114)
			(stroke
				(width 0.1)
				(type default)
			)
			(layer "F.Fab")
		)
		(fp_line
			(start -0.299974 -0.150114)
			(end 0.299974 -0.150114)
			(stroke
				(width 0.1)
				(type default)
			)
			(layer "F.Fab")
		)
		(fp_line
			(start 0.299974 -0.150114)
			(end 0.299974 0.150114)
			(stroke
				(width 0.1)
				(type default)
			)
			(layer "F.Fab")
		)
		(pad "1" smd rect
			(at -0.2667 0 270)
			(size 0.3048 0.381)
			(layers "F.Cu" "F.Mask" "F.Paste")
			(net "P5E_CPU1_P3_TX_C_DP<10>")
		)
		(pad "2" smd rect
			(at 0.2667 0 270)
			(size 0.3048 0.381)
			(layers "F.Cu" "F.Mask" "F.Paste")
			(net "P5E_CPU1_P3_TX_DP<10>")
		)
	)
	(footprint ""
		(layer "F.Cu")
		(at 411.734 -364.236 -90)
		(property "Reference" "R123"
			(at 0 0 270)
			(layer "F.SilkS")
			(hide yes)
			(effects
				(font
					(size 1.27 1.27)
				)
			)
		)
		(property "Value" ""
			(at 0 0 270)
			(layer "F.Fab")
			(effects
				(font
					(size 1.27 1.27)
				)
			)
		)
		(duplicate_pad_numbers_are_jumpers no)
		(fp_line
			(start -0.7874 0.4064)
			(end -0.7874 -0.4064)
			(stroke
				(width 0.1524)
				(type default)
			)
			(layer "F.SilkS")
		)
		(fp_line
			(start 0.7874 0.4064)
			(end -0.7874 0.4064)
			(stroke
				(width 0.1524)
				(type default)
			)
			(layer "F.SilkS")
		)
		(fp_line
			(start -0.7874 -0.4064)
			(end 0.7874 -0.4064)
			(stroke
				(width 0.1524)
				(type default)
			)
			(layer "F.SilkS")
		)
		(fp_line
			(start 0.7874 -0.4064)
			(end 0.7874 0.4064)
			(stroke
				(width 0.1524)
				(type default)
			)
			(layer "F.SilkS")
		)
		(fp_line
			(start -0.67945 0.3048)
			(end -0.67945 -0.305054)
			(stroke
				(width 0.1)
				(type default)
			)
			(layer "F.Fab")
		)
		(fp_line
			(start -0.12065 0.3048)
			(end -0.67945 0.3048)
			(stroke
				(width 0.1)
				(type default)
			)
			(layer "F.Fab")
		)
		(fp_line
			(start 0.120396 0.3048)
			(end 0.120396 0.2794)
			(stroke
				(width 0.1)
				(type default)
			)
			(layer "F.Fab")
		)
		(fp_line
			(start 0.67945 0.3048)
			(end 0.120396 0.3048)
			(stroke
				(width 0.1)
				(type default)
			)
			(layer "F.Fab")
		)
		(fp_line
			(start -0.12065 0.2794)
			(end -0.12065 0.3048)
			(stroke
				(width 0.1)
				(type default)
			)
			(layer "F.Fab")
		)
		(fp_line
			(start 0.120396 0.2794)
			(end -0.12065 0.2794)
			(stroke
				(width 0.1)
				(type default)
			)
			(layer "F.Fab")
		)
		(fp_line
			(start -0.12065 -0.2794)
			(end 0.12065 -0.2794)
			(stroke
				(width 0.1)
				(type default)
			)
			(layer "F.Fab")
		)
		(fp_line
			(start 0.12065 -0.2794)
			(end 0.12065 -0.3048)
			(stroke
				(width 0.1)
				(type default)
			)
			(layer "F.Fab")
		)
		(fp_line
			(start 0.12065 -0.3048)
			(end 0.67945 -0.3048)
			(stroke
				(width 0.1)
				(type default)
			)
			(layer "F.Fab")
		)
		(fp_line
			(start 0.67945 -0.3048)
			(end 0.67945 0.3048)
			(stroke
				(width 0.1)
				(type default)
			)
			(layer "F.Fab")
		)
		(fp_line
			(start -0.67945 -0.305054)
			(end -0.12065 -0.305054)
			(stroke
				(width 0.1)
				(type default)
			)
			(layer "F.Fab")
		)
		(fp_line
			(start -0.12065 -0.305054)
			(end -0.12065 -0.2794)
			(stroke
				(width 0.1)
				(type default)
			)
			(layer "F.Fab")
		)
		(pad "1" smd circle
			(at -0.40005 0 270)
			(size 0 0)
			(layers "F.Cu" "F.Mask" "F.Paste")
			(net "PVDD11_S3_P0_EN")
		)
		(pad "2" smd circle
			(at 0.40005 0 270)
			(size 0 0)
			(layers "F.Cu" "F.Mask" "F.Paste")
			(net "PVDD11_S3_P0_EN_R")
		)
	)
)
